FILE_TYPE = CONNECTIVITY;
{Allegro Design Entry HDL 16.6-p007 (v16-6-112F) 10/10/2012}
"PAGE_NUMBER" = 120;
0"NC";
1"GND\g";
2"P3V3_STBY\g";
3"IRQ_PCH_NIC_ALERT_N";
4"FM_OC0_USB_N";
5"IRQ_BMC_PCH_SCI_LPC_N";
6"LED_PCH_SATA_HDD_N";
7"FM_CPU_MSMI_LVT3_N";
8"FM_CPU0_RC_ERROR_N";
9"FM_CPU1_RC_ERROR_N";
10"FM_POST_CARD_PRES_BMC_N";
11"FM_CPLD_ADR_TRIGGER_N";
12"FM_CPU_ERR2_LVT3_N";
13"IRQ_BMC_PCH_NMI_STBY_N";
14"FM_ADR_SMI_GPIO_N";
15"IRQ_BMC_PCH_SMI_LPC_N";
16"IRQ_UV_DETECT_N";
17"FM_CPLD_ADR_TRIGGER_R_N";
18"FM_POST_CARD_PRES_BMC_R1_N";
19"SGPIO_PCH_SATA_DOUT0";
20"LED_PCH_SSATA_HDD_N";
21"FM_BIOS_TOP_SWAP";
22"FM_IE_DISABLE_N";
23"IRQ_SML1_PMBUS_ALERT_R1_N";
24"SGPIO_PCH_SATA_CLOCK";
25"JTAG_PCH_PLD_TCK";
26"JTAG_PCH_PLD_TDI";
27"JTAG_PCH_PLD_TMS";
28"JTAG_PCH_PLD_TDO";
29"SGPIO_PCH_SATA_LOAD";
30"FM_BMC_READY_R1_N";
31"FM_HSC_TIMER_EXP_N";
32"FM_UARTSW_MSB_N";
33"FM_CPU0_RC_EN";
34"FM_SOL_UART_CH_SEL";
35"FM_BIOS_SMI_ACTIVE_N";
36"FM_NMI_EVENT_N";
37"FM_BOARD_SKU_ID3";
38"FM_BOARD_SKU_ID2";
39"FM_BOARD_SKU_ID1";
40"LED_GBE_P0_0";
41"LED_GBE_P1_0";
42"LED_GBE_P1_1";
43"FM_BIOS_USB_RECOVERY";
44"IRQ_SML1_PMBUS_ALERT_N";
45"SMB_LAN_STBY_LVC3_SDA_R2";
46"FM_CPU0_RC_ERROR_R1_N";
47"SGPIO_PCH_SSATA_LOAD";
48"SGPIO_PCH_SSATA_CLOCK";
49"FM_CPU1_RC_ERROR_R1_N";
50"FM_BIOS_SMI_ACTIVE_N";
51"FM_CPU1_RC_ERROR_N";
52"IRQ_DIMM_SAVE_LVT3_N";
53"IRQ_FORCE_NM_THROTTLE_N";
54"FM_FORCE_ADR_N";
55"FM_BACKUP_BIOS_SEL_N";
56"FM_UARTSW_LSB_N";
57"FM_MEM_THERM_EVENT_PCH_N";
58"FM_MP_PS_FAIL_N";
59"FM_MP_PS_REDUNDANT_LOST_N";
60"SMB_LAN_STBY_LVC3_SCL_R2";
61"JTAG_PCH_GBE_TRST_N";
62"FM_CPU1_RC_ERROR_R_N";
63"IRQ_DIMM_SAVE_LVT3_R_N";
64"JTAG_PCH_GBE_TDO";
65"TP_PCH_GPP_J21";
66"FM_GBE2_LVC3_MOD_ABS";
67"IRQ_BOARD_BMC_ALERT_N";
68"JTAG_PCH_GBE_TDI";
69"JTAG_PCH_GBE_TMS";
70"JTAG_PCH_GBE_CLK";
71"SMB_VR_STBY_LVC3_SCL_R1";
72"FM_10GBE_LOM_DISABLE_N";
73"PU_10GBE_LOM_PCI_DISABLE_N";
74"FM_BIOS_MRC_DEBUG_MSG_DIS_N";
75"FM_GBE3_LVC3_MOD_ABS";
76"SMB_PCH_MEZZ_LOM3_SDA";
77"SMB_PCH_MEZZ_LOM2_SDA";
78"SMB_VR_STBY_LVC3_SDA_R1";
79"PU_ADR_TIMER_HOLD_OFF_N";
80"SMB_LAN_STBY_LVC3_SCL_R1";
81"A_RCOMP_3P3";
82"FM_BMC_READY_N";
83"IRQ_OC_DETECT_N";
84"FM_ADR_COMPLETE_R1";
85"FM_BOARD_SKU_ID0";
86"FM_SSATA_PCIE_M2_SEL";
87"FM_PCH_BMC_THERMTRIP_N";
88"FM_BMC_NMI_N";
89"FP_PWR_ID_LED_N";
90"FM_OC_DETECT_EN_N";
91"SMB_LAN_STBY_LVC3_SDA_R1";
92"FM_FLASH_ATTACH_CFG_STRAP";
93"FM_GBE1_LVC3_MOD_ABS";
94"FM_GBE0_LVC3_MOD_ABS";
95"SMB_PCH_MEZZ_LOM3_SCL";
96"SMB_PCH_MEZZ_LOM2_SCL";
97"SMB_PCH_MEZZ_LOM1_SDA";
98"SMB_PCH_MEZZ_LOM0_SDA";
99"LED_GBE_P3_1";
100"LED_GBE_P3_0";
101"LED_GBE_P2_1";
102"LED_GBE_P2_0";
103"LED_GBE_P0_1";
104"FM_ADR_COMPLETE";
105"FM_BOARD_SKU_ID4";
106"FM_CPU1_THERMTRIP_LATCH_LVT3_N";
107"TP_PCH_GPP_J19";
108"TP_PCH_GPP_J17";
109"SMB_PCH_MEZZ_LOM0_SCL";
110"SMB_PCH_MEZZ_LOM1_SCL";
111"TP_PCH_GPP_J23";
%"LBG_CORE_QAT_EXT_D"
"7","(-3750,2800)","0","mstr_u_proc","I147";
;
CDS_SEC"7"
LOCATION"U7C1"
PART_NUMBER"H91415-002"
MATERIAL"IC"
CDS_LOCATION"U7C1"
BOM_COST"SB"
CDS_LIB"mstr_u_proc"
SEC"7"
SEC_TYPE"BGA1"
ROOM"SB"
PACK_TYPE"BGA1";
"GPP_J9_LAN_I2C_SDA_MDIO_P0"
$PN"BN3"98;
"GPP_J8_LAN_I2C_SCL_MDC_P0"
$PN"BM4"109;
"GPP_J7_LAN_LED_P3_1"
$PN"BM2"99;
"GPP_J6_LAN_LED_P3_0"
$PN"CA13"100;
"GPP_J5_LAN_LED_P2_1"
$PN"BU6"101;
"GPP_J4_LAN_LED_P2_0"
$PN"BL3"102;
"GPP_J3_LAN_LED_P1_1"
$PN"BK2"42;
"GPP_J2_LAN_LED_P1_0"
$PN"BP4"41;
"GPP_J23_LAN_SDP_P3_1"
$PN"BV14"111;
"GPP_J22_LAN_SDP_P3_0"
$PN"BY12"75;
"GPP_J21_LAN_SDP_P2_1"
$PN"BV12"65;
"GPP_J20_LAN_SDP_P2_0"
$PN"BW13"66;
"GPP_J1_LAN_LED_P0_1"
$PN"BK4"103;
"GPP_J19_LAN_SDP_P1_1"
$PN"BY14"107;
"GPP_J18_LAN_SDP_P1_0"
$PN"BY10"93;
"GPP_J17_LAN_SDP_P0_1"
$PN"CA11"108;
"GPP_J16_LAN_SDP_P0_0"
$PN"BV10"94;
"GPP_J15_LAN_I2C_SDA_MDIO_P3"
$PN"BW9"76;
"GPP_J14_LAN_I2C_SCL_MDC_P3"
$PN"BW6"95;
"GPP_J13_LAN_I2C_SDA_MDIO_P2"
$PN"BW11"77;
"GPP_J12_LAN_I2C_SCL_MDC_P2"
$PN"BT5"96;
"GPP_J11_LAN_I2C_SDA_MDIO_P1"
$PN"BV8"97;
"GPP_J10_LAN_I2C_SCL_MDC_P1"
$PN"BW5"110;
"GPP_J0_LAN_LED_P0_0"
$PN"BL1"40;
"GPP_I9_LAN_DIS_N"
$PN"BY21"72;
"GPP_I8_PCI_DIS_N"
$PN"BW22"73;
"GPP_I7_LAN_TRST_N"
$PN"CA24"61;
"GPP_I6_RESET_DONE"
$PN"BV23"62;
"GPP_I5_DO_RESET_OUT_N"
$PN"BW24"67;
"GPP_I4_DO_RESET_IN_N"
$PN"BW20"63;
"GPP_I3_LAN_TDI"
$PN"BY23"68;
"GPP_I2_LAN_TMS"
$PN"CA22"69;
"GPP_I1_LAN_TCK"
$PN"BV21"70;
"GPP_I10"
$PN"BV25"74;
"GPP_I0_LAN_TDO"
$PN"CA20"64;
"GPP_H9_SRCCLKREQ15_N"
$PN"BE2"0;
"GPP_H8_SRCCLKREQ14_N"
$PN"AR3"0;
"GPP_H7_SRCCLKREQ13_N"
$PN"AV1"0;
"GPP_H6_SRCCLKREQ12_N"
$PN"AW2"0;
"GPP_H5_SRCCLKREQ11_N"
$PN"AY3"0;
"GPP_H4_SRCCLKREQ10_N"
$PN"AT2"0;
"GPP_H3_SRCCLKREQ9_N"
$PN"AR1"0;
"GPP_H2_SRCCLKREQ8_N"
$PN"AV3"0;
"GPP_H23_SSATAXPCIE5_SSATAGP5"
$PN"BH4"86;
"GPP_H22_SSATAXPCIE4_SSATAGP4"
$PN"BH2"87;
"GPP_H21_SSATAXPCIE3_SSATAGP3"
$PN"BA2"50;
"GPP_H20_SSATAXPCIE2_SSATAGP2"
$PN"BF3"88;
"GPP_H1_SRCCLKREQ7_N"
$PN"AW4"55;
"GPP_H19_SSATAXPCIE1_SSATAGP1"
$PN"BD3"89;
"GPP_H18_SML4ALERT_N_IE_N"
$PN"BC4"90;
"GPP_H17_SML4DATA_IE"
$PN"BE4"91;
"GPP_H16_SML4CLK_IE"
$PN"BF1"80;
"GPP_H15_SML3ALERT_N_IE_N"
$PN"BB3"79;
"GPP_H14_SML3DATA_IE"
$PN"BC2"0;
"GPP_H13_SML3CLK_IE"
$PN"AY1"0;
"GPP_H12_SML2ALERT_N_IE_N"
$PN"BB1"92;
"GPP_H11_SML2DATA_IE"
$PN"BD1"78;
"GPP_H10_SML2CLK_IE"
$PN"BA4"71;
"GPP_H0_SRCCLKREQ6_N"
$PN"AT4"56;
"GPP_G9_FANPWM1_FAMPWM1IE"
$PN"AV11"0;
"GPP_G8_FANPWM0_FANPWM0IE"
$PN"BG11"0;
"GPP_G7_FANTACH7_FANTACH7IE"
$PN"AY15"0;
"GPP_G6_FANTACH6_FANTACH6IE"
$PN"AV18"106;
"GPP_G5_FANTACH5_FANTACH5IE"
$PN"AW20"0;
"GPP_G4_FANTACH4_FANTACH4IE"
$PN"BA9"0;
"GPP_G3_FANTACH3_FANTACH3IE"
$PN"AY7"0;
"GPP_G2_FANTACH2_FANTACH2IE"
$PN"BE22"0;
"GPP_G23_SSATAXPCIE0_SSATAGP0"
$PN"BA13"32;
"GPP_G22_SSATA_DEVSLP2"
$PN"BD20"33;
"GPP_G21_SSATA_DEVSLP1"
$PN"BG7"34;
"GPP_G20_SSATA_DEVSLP0"
$PN"BA17"53;
"GPP_G1_FANTACH1_FANTACH1IE"
$PN"AV15"0;
"GPP_G19_SMI_N"
$PN"BE15"35;
"GPP_G18_NMI_N"
$PN"BE7"36;
"GPP_G17_ADR_COMPLETE"
$PN"BD9"84;
"GPP_G16"
$PN"BD17"105;
"GPP_G15"
$PN"BE18"37;
"GPP_G14"
$PN"AV7"38;
"GPP_G13"
$PN"AY18"39;
"GPP_G12"
$PN"BD13"85;
"GPP_G11_FANPWM3_FANPMW3IE"
$PN"BA20"0;
"GPP_G10_FANPWM2_FANPWM2IE"
$PN"BE11"0;
"GPP_G0_FANTACH0_FANTACH0IE"
$PN"AY11"0;
"GPP_F9_SATA_DEVSLP7"
$PN"AR20"28;
"GPP_F8_SATA_DEVSLP6"
$PN"AH9"27;
"GPP_F7_SATA_DEVSLP5"
$PN"AK17"26;
"GPP_F6_SATA_DEVSLP4"
$PN"AL18"25;
"GPP_F5_SATA_DEVSLP3"
$PN"AH17"43;
"GPP_F4_SATAXPCIE7_SATAGP7"
$PN"AH13"30;
"GPP_F3_SATAXPCIE6_SATAGP6"
$PN"AK13"59;
"GPP_F2_SATAXPCIE5_SATAGP5"
$PN"AK20"58;
"GPP_F23_SSATA_SLOAD"
$PN"AU17"47;
"GPP_F22_SSATA_SCLOCK"
$PN"AP18"48;
"GPP_F21_LAN_SMBALRT_N"
$PN"AR17"3;
"GPP_F20_LAN_SMBDATA"
$PN"AU20"45;
"GPP_F1_SATAXPCIE4_SATAGP4"
$PN"AK9"31;
"GPP_F19_LAN_SMBCLK"
$PN"AU9"60;
"GPP_F18_USB2_OC7_N"
$PN"AL15"57;
"GPP_F17_USB2_OC6_N"
$PN"AP15"21;
"GPP_F16_USB2_OC5_N"
$PN"AU13"22;
"GPP_F15_USB2_OC4_N"
$PN"AR13"54;
"GPP_F14_SSATA_LED_N"
$PN"AL11"20;
"GPP_F13_SATA_SDATAOUT0"
$PN"AP11"19;
"GPP_F12_SATA_SDATAOUT1"
$PN"AP7"23;
"GPP_F11_SATA_SLOAD"
$PN"AR9"29;
"GPP_F10_SATA_SCLOCK"
$PN"AL7"24;
"GPP_F0_SATAXPCIE3_SATAGP3"
$PN"AG7"83;
"GPP_E9_USB2_OC0_N"
$PN"BL48"4;
"GPP_E8_SATA_LED_N"
$PN"AV56"6;
"GPP_E7_CPU_GP1"
$PN"BJ48"14;
"GPP_E6_SATA_DEVSLP2"
$PN"BB52"13;
"GPP_E5_SATA_DEVSLP1"
$PN"AT52"7;
"GPP_E4_SATA_DEVSLP0"
$PN"AV52"12;
"GPP_E3_CPU_GP0"
$PN"BE52"17;
"GPP_E2_SATAXPCIE2_SATAGP2"
$PN"BG52"18;
"GPP_E1_SATAXPCIE1_SATAGP1"
$PN"AY52"49;
"GPP_E12_USB2_OC3_N"
$PN"AU58"16;
"GPP_E11_USB2_OC2_N"
$PN"AW54"15;
"GPP_E10_USB2_OC1_N"
$PN"BN48"5;
"GPP_E0_SATAXPCIE0_SATAGP0"
$PN"BH50"46;
"GPIO_RCOMP_3P3"
$PN"BY25"81;
%"RES"
"1","(-6650,3850)","0","mstr_discrete","I218";
;
CDS_SEC"1"
LOCATION"R2M1"
TOLERANCE"1%"
VALUE"33.2"
MATERIAL"CHIP"
WATTAGE"1/16W"
PACK_TYPE"0402"
PART_NUMBER"G21796-074"
ROOM"CPLD"
CDS_LOCATION"R2M1"
SEC"1"
SEC_TYPE"0402"
CDS_LIB"mstr_discrete";
"B"
$PN"2"17;
"A"
$PN"1"11;
%"RES"
"1","(-6100,2050)","0","mstr_discrete","I219";
;
CDS_SEC"1"
MATERIAL"CHIP"
VALUE"33.2"
PACK_TYPE"0402"
TOLERANCE"1%"
LOCATION"R2N26"
WATTAGE"1/16W"
PART_NUMBER"G21796-074"
CDS_LIB"mstr_discrete"
SEC_TYPE"0402"
SEC"1"
CDS_LOCATION"R2N26"
ROOM"CPLD";
"B"
$PN"2"84;
"A"
$PN"1"104;
%"GND"
"1","(-950,2975)","0","mstr_symbols","I266";
;
VOLTAGE"0.0V"
HDL_POWER"GND"
CDS_LIB"mstr_symbols"
SIZE"1B"
BODY_TYPE"PLUMBING";
"A\NAC"1;
%"RES"
"1","(-6650,3800)","0","mstr_discrete","I269";
;
PART_NUMBER"G21497-005"
VALUE"0.0"
TOLERANCE"5%"
PACK_TYPE"0402"
WATTAGE"1/16W"
LOCATION"R7W8"
CDS_LOCATION"R7W8"
CDS_LIB"mstr_discrete"
BOM_COST"PROC_SIDEBAND"
MATERIAL"CHIP"
ROOM"CPU0"
SEC_TYPE"0402"
SEC"1"
CDS_SEC"1";
"B"
$PN"2"18;
"A"
$PN"1"10;
%"RES"
"1","(-6200,3700)","0","mstr_discrete","I270";
;
LOCATION"R7W10"
PACK_TYPE"0402"
TOLERANCE"5%"
WATTAGE"1/16W"
VALUE"0.0"
PART_NUMBER"G21497-005"
CDS_LOCATION"R7W10"
CDS_LIB"mstr_discrete"
BOM_COST"PROC_SIDEBAND"
MATERIAL"CHIP"
ROOM"CPU0"
SEC_TYPE"0402"
SEC"1"
CDS_SEC"1";
"B"
$PN"2"46;
"A"
$PN"1"8;
%"RES"
"1","(-6400,3750)","0","mstr_discrete","I271";
;
PACK_TYPE"0402"
WATTAGE"1/16W"
TOLERANCE"5%"
VALUE"0.0"
LOCATION"R7W12"
PART_NUMBER"G21497-005"
CDS_LOCATION"R7W12"
CDS_LIB"mstr_discrete"
BOM_COST"PROC_SIDEBAND"
MATERIAL"CHIP"
ROOM"CPU0"
SEC_TYPE"0402"
SEC"1"
CDS_SEC"1";
"B"
$PN"2"49;
"A"
$PN"1"9;
%"RES"
"1","(-950,2800)","0","mstr_discrete","I273";
;
PART_NUMBER"G21497-005"
TOLERANCE"5%"
WATTAGE"1/16W"
PACK_TYPE"0402"
VALUE"0.0"
LOCATION"R7W11"
CDS_LOCATION"R7W11"
CDS_SEC"1"
SEC"1"
SEC_TYPE"0402"
ROOM"CPU0"
MATERIAL"CHIP"
BOM_COST"PROC_SIDEBAND"
CDS_LIB"mstr_discrete";
"B"
$PN"2"51;
"A"
$PN"1"62;
%"RES"
"1","(-6775,2650)","0","mstr_discrete","I274";
;
PART_NUMBER"G21497-005"
TOLERANCE"5%"
VALUE"0.0"
WATTAGE"1/16W"
PACK_TYPE"0402"
LOCATION"R7W14"
CDS_LOCATION"R7W14"
SEC"1"
SEC_TYPE"0402"
ROOM"CPU0"
MATERIAL"CHIP"
BOM_COST"PROC_SIDEBAND"
CDS_LIB"mstr_discrete"
CDS_SEC"1";
"B"
$PN"2"30;
"A"
$PN"1"82;
%"RES"
"2","(-1400,3050)","1","mstr_discrete","I275";
;
CDS_SEC"1"
MATERIAL"CHIP"
PACK_TYPE"0402"
PART_NUMBER"G21796-017"
LOCATION"R8C21"
TOLERANCE"1%"
WATTAGE"1/16W"
VALUE"100.0"
ROOM"SB"
SEC"1"
SEC_TYPE"0402"
CDS_LOCATION"R8C21"
CDS_LIB"mstr_discrete";
"A"
$PN"1"81;
"B"
$PN"2"1;
%"RES"
"1","(-950,2700)","0","mstr_discrete","I276";
;
VALUE"0.0"
LOCATION"R7W16"
PACK_TYPE"0402"
TOLERANCE"5%"
WATTAGE"1/16W"
PART_NUMBER"G21497-005"
CDS_LOCATION"R7W16"
CDS_SEC"1"
SEC"1"
SEC_TYPE"0402"
ROOM"CPU0"
MATERIAL"CHIP"
BOM_COST"PROC_SIDEBAND"
CDS_LIB"mstr_discrete";
"B"
$PN"2"52;
"A"
$PN"1"63;
%"RES"
"1","(-6850,3050)","0","mstr_discrete","I277";
;
TOLERANCE"5%"
WATTAGE"1/16W"
VALUE"0.0"
PACK_TYPE"0402"
LOCATION"R7W18"
PART_NUMBER"G21497-005"
CDS_LOCATION"R7W18"
CDS_LIB"mstr_discrete"
BOM_COST"PROC_SIDEBAND"
MATERIAL"CHIP"
ROOM"CPU0"
SEC_TYPE"0402"
SEC"1"
CDS_SEC"1";
"B"
$PN"2"23;
"A"
$PN"1"44;
%"RES"
"2","(-6500,4500)","0","mstr_discrete","I278";
;
CDS_SEC"1"
MATERIAL"CHIP"
WATTAGE"1/16W"
VALUE"4.75K"
PART_NUMBER"G21796-072"
POP"NOPOP"
PACK_TYPE"0402"
TOLERANCE"1%"
LOCATION"R7W20"
CDS_LOCATION"R7W20"
CDS_LIB"mstr_discrete"
ROOM"CPU0"
SEC"1"
SEC_TYPE"0402";
"A"
$PN"1"2;
"B"
$PN"2"18;
%"P3V3_STBY"
"1","(-6500,4700)","0","mstr_symbols","I279";
;
HDL_POWER"P3V3_STBY"
BODY_TYPE"PLUMBING"
SIZE"1B"
CDS_LIB"mstr_symbols"
VOLTAGE"3.3V";
"G\NAC"2;
END.
